# T6G (Grand Teton) — schematic netlist excerpt (pin names and nets, part order shuffled) for the footprints in the layout excerpt that follows; sources: Cadence DE-HDL packaged netlist, KiCad conversion of 04192023_DAF0TMB3IC0_F0TG_MB_C_brd_V02_OCP.brd

PR419  Q_RES  0 5% CHIP  pkg 0402LF  page 207 : A = NC_PVDD11_S3_P0_IMON7 ; B = GND
R6315  Q_RES  10K 1% CHIP  pkg 0402LF  page 178 : A = P3V3_AUX ; B = USB_HUB2_TI_OVERCUR2

(kicad_pcb
	(version 20260206)
	(generator "pcbnew")
	(generator_version "10.0")
	(general
		(thickness 1.6)
		(legacy_teardrops no)
	)
	(paper "A4")
	(title_block
		(title "04192023_DAF0TMB3IC0_F0TG_MB_C_brd_V02_OCP.brd")
		(comment 1 "Grand Teton / footprints 1227-1228 of 8354")
	)
	(layers
		(0 "F.Cu" signal "TOP")
		(4 "In1.Cu" signal "GND")
		(6 "In2.Cu" signal "IN1")
		(8 "In3.Cu" signal "GND1")
		(10 "In4.Cu" signal "IN2")
		(12 "In5.Cu" signal "GND2")
		(14 "In6.Cu" signal "IN3")
		(16 "In7.Cu" signal "GND3")
		(18 "In8.Cu" signal "VCC")
		(20 "In9.Cu" signal "VCC1")
		(22 "In10.Cu" signal "GND4")
		(24 "In11.Cu" signal "IN4")
		(26 "In12.Cu" signal "GND5")
		(28 "In13.Cu" signal "IN5")
		(30 "In14.Cu" signal "GND6")
		(32 "In15.Cu" signal "IN6")
		(34 "In16.Cu" signal "GND7")
		(2 "B.Cu" signal "BOTTOM")
		(9 "F.Adhes" user "F.Adhesive")
		(11 "B.Adhes" user "B.Adhesive")
		(13 "F.Paste" user "Package Geometry/Pastemask Top")
		(15 "B.Paste" user "Package Geometry/Pastemask Bottom")
		(5 "F.SilkS" user "Ref Des/Silkscreen Top")
		(7 "B.SilkS" user "Ref Des/Silkscreen Bottom")
		(1 "F.Mask" user "Board Geometry/Soldermask Top")
		(3 "B.Mask" user "Board Geometry/Soldermask Bottom")
		(17 "Dwgs.User" user "User.Drawings")
		(19 "Cmts.User" user "User.Comments")
		(21 "Eco1.User" user "User.Eco1")
		(23 "Eco2.User" user "User.Eco2")
		(25 "Edge.Cuts" user "Board Geometry/Outline")
		(27 "Margin" user)
		(31 "F.CrtYd" user "Package Geometry/Place Bound Top")
		(29 "B.CrtYd" user "Package Geometry/Place Bound Bottom")
		(35 "F.Fab" user "Ref Des/Assembly Top")
		(33 "B.Fab" user "Ref Des/Assembly Bottom")
	)
	(footprint ""
		(layer "F.Cu")
		(at 422.763696 -357.688134 -90)
		(property "Reference" "PR419"
			(at 0 0 270)
			(layer "F.SilkS")
			(hide yes)
			(effects
				(font
					(size 1.27 1.27)
				)
			)
		)
		(property "Value" ""
			(at 0 0 270)
			(layer "F.Fab")
			(effects
				(font
					(size 1.27 1.27)
				)
			)
		)
		(duplicate_pad_numbers_are_jumpers no)
		(fp_line
			(start -0.7874 0.4064)
			(end -0.7874 -0.4064)
			(stroke
				(width 0.1524)
				(type default)
			)
			(layer "F.SilkS")
		)
		(fp_line
			(start 0.7874 0.4064)
			(end -0.7874 0.4064)
			(stroke
				(width 0.1524)
				(type default)
			)
			(layer "F.SilkS")
		)
		(fp_line
			(start -0.7874 -0.4064)
			(end 0.7874 -0.4064)
			(stroke
				(width 0.1524)
				(type default)
			)
			(layer "F.SilkS")
		)
		(fp_line
			(start 0.7874 -0.4064)
			(end 0.7874 0.4064)
			(stroke
				(width 0.1524)
				(type default)
			)
			(layer "F.SilkS")
		)
		(fp_line
			(start -0.67945 0.3048)
			(end -0.67945 -0.305054)
			(stroke
				(width 0.1)
				(type default)
			)
			(layer "F.Fab")
		)
		(fp_line
			(start -0.12065 0.3048)
			(end -0.67945 0.3048)
			(stroke
				(width 0.1)
				(type default)
			)
			(layer "F.Fab")
		)
		(fp_line
			(start 0.120396 0.3048)
			(end 0.120396 0.2794)
			(stroke
				(width 0.1)
				(type default)
			)
			(layer "F.Fab")
		)
		(fp_line
			(start 0.67945 0.3048)
			(end 0.120396 0.3048)
			(stroke
				(width 0.1)
				(type default)
			)
			(layer "F.Fab")
		)
		(fp_line
			(start -0.12065 0.2794)
			(end -0.12065 0.3048)
			(stroke
				(width 0.1)
				(type default)
			)
			(layer "F.Fab")
		)
		(fp_line
			(start 0.120396 0.2794)
			(end -0.12065 0.2794)
			(stroke
				(width 0.1)
				(type default)
			)
			(layer "F.Fab")
		)
		(fp_line
			(start -0.12065 -0.2794)
			(end 0.12065 -0.2794)
			(stroke
				(width 0.1)
				(type default)
			)
			(layer "F.Fab")
		)
		(fp_line
			(start 0.12065 -0.2794)
			(end 0.12065 -0.3048)
			(stroke
				(width 0.1)
				(type default)
			)
			(layer "F.Fab")
		)
		(fp_line
			(start 0.12065 -0.3048)
			(end 0.67945 -0.3048)
			(stroke
				(width 0.1)
				(type default)
			)
			(layer "F.Fab")
		)
		(fp_line
			(start 0.67945 -0.3048)
			(end 0.67945 0.3048)
			(stroke
				(width 0.1)
				(type default)
			)
			(layer "F.Fab")
		)
		(fp_line
			(start -0.67945 -0.305054)
			(end -0.12065 -0.305054)
			(stroke
				(width 0.1)
				(type default)
			)
			(layer "F.Fab")
		)
		(fp_line
			(start -0.12065 -0.305054)
			(end -0.12065 -0.2794)
			(stroke
				(width 0.1)
				(type default)
			)
			(layer "F.Fab")
		)
		(pad "1" smd circle
			(at -0.40005 0 270)
			(size 0 0)
			(layers "F.Cu" "F.Mask" "F.Paste")
			(net "NC_PVDD11_S3_P0_IMON7")
		)
		(pad "2" smd circle
			(at 0.40005 0 270)
			(size 0 0)
			(layers "F.Cu" "F.Mask" "F.Paste")
			(net "GND")
		)
	)
	(footprint ""
		(layer "F.Cu")
		(at 105.485946 -54.882034 -90)
		(property "Reference" "R6315"
			(at 0 0 270)
			(layer "F.SilkS")
			(hide yes)
			(effects
				(font
					(size 1.27 1.27)
				)
			)
		)
		(property "Value" ""
			(at 0 0 270)
			(layer "F.Fab")
			(effects
				(font
					(size 1.27 1.27)
				)
			)
		)
		(duplicate_pad_numbers_are_jumpers no)
		(fp_line
			(start -0.7874 0.4064)
			(end -0.7874 -0.4064)
			(stroke
				(width 0.1524)
				(type default)
			)
			(layer "F.SilkS")
		)
		(fp_line
			(start 0.7874 0.4064)
			(end -0.7874 0.4064)
			(stroke
				(width 0.1524)
				(type default)
			)
			(layer "F.SilkS")
		)
		(fp_line
			(start -0.7874 -0.4064)
			(end 0.7874 -0.4064)
			(stroke
				(width 0.1524)
				(type default)
			)
			(layer "F.SilkS")
		)
		(fp_line
			(start 0.7874 -0.4064)
			(end 0.7874 0.4064)
			(stroke
				(width 0.1524)
				(type default)
			)
			(layer "F.SilkS")
		)
		(fp_line
			(start -0.67945 0.3048)
			(end -0.67945 -0.305054)
			(stroke
				(width 0.1)
				(type default)
			)
			(layer "F.Fab")
		)
		(fp_line
			(start -0.12065 0.3048)
			(end -0.67945 0.3048)
			(stroke
				(width 0.1)
				(type default)
			)
			(layer "F.Fab")
		)
		(fp_line
			(start 0.120396 0.3048)
			(end 0.120396 0.2794)
			(stroke
				(width 0.1)
				(type default)
			)
			(layer "F.Fab")
		)
		(fp_line
			(start 0.67945 0.3048)
			(end 0.120396 0.3048)
			(stroke
				(width 0.1)
				(type default)
			)
			(layer "F.Fab")
		)
		(fp_line
			(start -0.12065 0.2794)
			(end -0.12065 0.3048)
			(stroke
				(width 0.1)
				(type default)
			)
			(layer "F.Fab")
		)
		(fp_line
			(start 0.120396 0.2794)
			(end -0.12065 0.2794)
			(stroke
				(width 0.1)
				(type default)
			)
			(layer "F.Fab")
		)
		(fp_line
			(start -0.12065 -0.2794)
			(end 0.12065 -0.2794)
			(stroke
				(width 0.1)
				(type default)
			)
			(layer "F.Fab")
		)
		(fp_line
			(start 0.12065 -0.2794)
			(end 0.12065 -0.3048)
			(stroke
				(width 0.1)
				(type default)
			)
			(layer "F.Fab")
		)
		(fp_line
			(start 0.12065 -0.3048)
			(end 0.67945 -0.3048)
			(stroke
				(width 0.1)
				(type default)
			)
			(layer "F.Fab")
		)
		(fp_line
			(start 0.67945 -0.3048)
			(end 0.67945 0.3048)
			(stroke
				(width 0.1)
				(type default)
			)
			(layer "F.Fab")
		)
		(fp_line
			(start -0.67945 -0.305054)
			(end -0.12065 -0.305054)
			(stroke
				(width 0.1)
				(type default)
			)
			(layer "F.Fab")
		)
		(fp_line
			(start -0.12065 -0.305054)
			(end -0.12065 -0.2794)
			(stroke
				(width 0.1)
				(type default)
			)
			(layer "F.Fab")
		)
		(pad "1" smd circle
			(at -0.40005 0 270)
			(size 0 0)
			(layers "F.Cu" "F.Mask" "F.Paste")
			(net "P3V3_AUX")
		)
		(pad "2" smd circle
			(at 0.40005 0 270)
			(size 0 0)
			(layers "F.Cu" "F.Mask" "F.Paste")
			(net "USB_HUB2_TI_OVERCUR2")
		)
	)
)
